# BASEBOARD_FAB2 (Tioga Pass) — schematic netlist excerpt (pin names and nets, part order shuffled) for the footprints in the layout excerpt that follows; sources: Cadence DE-HDL packaged netlist, KiCad conversion of Wiwynn_Tioga_Pass_MB.brd

C6D4  CAP_A  22.0UF 4V 20% X6S  pkg 0603V  page 42 : A = PVCCIO_CPU0 ; B = GND

(kicad_pcb
	(version 20260206)
	(generator "pcbnew")
	(generator_version "10.0")
	(general
		(thickness 1.6)
		(legacy_teardrops no)
	)
	(paper "A4")
	(title_block
		(title "Wiwynn_Tioga_Pass_MB.brd")
		(comment 1 "Tioga Pass / footprints 1252-1252 of 4770")
	)
	(layers
		(0 "F.Cu" signal "TOP")
		(4 "In1.Cu" signal "L2GND")
		(6 "In2.Cu" signal "L3")
		(8 "In3.Cu" signal "L4GND")
		(10 "In4.Cu" signal "L5")
		(12 "In5.Cu" signal "L6GND")
		(14 "In6.Cu" signal "L7VCC")
		(16 "In7.Cu" signal "L8VCC")
		(18 "In8.Cu" signal "L9GND")
		(20 "In9.Cu" signal "L10")
		(22 "In10.Cu" signal "L11GND")
		(24 "In11.Cu" signal "L12")
		(26 "In12.Cu" signal "L13GND")
		(2 "B.Cu" signal "BOTTOM")
		(9 "F.Adhes" user "F.Adhesive")
		(11 "B.Adhes" user "B.Adhesive")
		(13 "F.Paste" user "Package Geometry/Pastemask Top")
		(15 "B.Paste" user "Package Geometry/Pastemask Bottom")
		(5 "F.SilkS" user "Ref Des/Silkscreen Top")
		(7 "B.SilkS" user "Ref Des/Silkscreen Bottom")
		(1 "F.Mask" user "Board Geometry/Soldermask Top")
		(3 "B.Mask" user "Board Geometry/Soldermask Bottom")
		(17 "Dwgs.User" user "User.Drawings")
		(19 "Cmts.User" user "User.Comments")
		(21 "Eco1.User" user "User.Eco1")
		(23 "Eco2.User" user "User.Eco2")
		(25 "Edge.Cuts" user "Board Geometry/Outline")
		(27 "Margin" user)
		(31 "F.CrtYd" user "Package Geometry/Place Bound Top")
		(29 "B.CrtYd" user "Package Geometry/Place Bound Bottom")
		(35 "F.Fab" user "Ref Des/Assembly Top")
		(33 "B.Fab" user "Ref Des/Assembly Bottom")
	)
	(footprint ""
		(layer "F.Cu")
		(at 279.6032 -79.6036 180)
		(property "Reference" "C6D4"
			(at 0 0 180)
			(layer "F.SilkS")
			(hide yes)
			(effects
				(font
					(size 1.27 1.27)
				)
			)
		)
		(property "Value" ""
			(at 0 0 180)
			(layer "F.Fab")
			(effects
				(font
					(size 1.27 1.27)
				)
			)
		)
		(duplicate_pad_numbers_are_jumpers no)
		(fp_poly
			(pts
				(xy -0.4953 -0.2032) (xy 0.4953 -0.2032) (xy 0.4953 1.6002) (xy -0.4953 1.6002)
			)
			(stroke
				(width 0)
				(type default)
			)
			(fill no)
			(layer "F.CrtYd")
		)
		(fp_line
			(start 0.4953 1.6002)
			(end -0.4953 1.6002)
			(stroke
				(width 0.1)
				(type default)
			)
			(layer "F.Fab")
		)
		(fp_line
			(start 0.4953 -0.2032)
			(end 0.4953 1.6002)
			(stroke
				(width 0.1)
				(type default)
			)
			(layer "F.Fab")
		)
		(fp_line
			(start -0.4953 1.6002)
			(end -0.4953 -0.2032)
			(stroke
				(width 0.1)
				(type default)
			)
			(layer "F.Fab")
		)
		(fp_line
			(start -0.4953 -0.2032)
			(end 0.4953 -0.2032)
			(stroke
				(width 0.1)
				(type default)
			)
			(layer "F.Fab")
		)
		(pad "1" smd rect
			(at 0 0 180)
			(size 0.762 0.889)
			(layers "F.Cu" "F.Mask" "F.Paste")
			(net "PVCCIO_CPU0")
		)
		(pad "2" smd rect
			(at 0 1.397 180)
			(size 0.762 0.889)
			(layers "F.Cu" "F.Mask" "F.Paste")
			(net "GND")
		)
		(zone
			(layer "F.Cu")
			(hatch none 0.5)
			(connect_pads
				(clearance 0)
			)
			(min_thickness 0.25)
			(keepout
				(tracks not_allowed)
				(vias allowed)
				(pads allowed)
				(copperpour not_allowed)
				(footprints allowed)
			)
			(placement
				(enabled no)
				(sheetname "")
			)
			(fill
				(thermal_gap 0.5)
				(thermal_bridge_width 0.5)
				(island_removal_mode 0)
			)
			(polygon
				(pts
					(xy 279.9842 -80.0481) (xy 279.2222 -80.0481) (xy 279.2222 -80.5561) (xy 279.9842 -80.5561)
				)
			)
		)
	)
)
